(kicad_pcb
	(version 20241229)
	(generator "pcbnew")
	(generator_version "9.0")
	(general
		(thickness 1.61)
		(legacy_teardrops no)
	)
	(paper "A3")
	(title_block
		(title "RDIMM DDR5 Tester")
		(date "2026-05-21")
		(rev "2.2.0")
		(company "Antmicro")
		(comment 9 "footprints 504-507 of 796")
	)
	(layers
		(0 "F.Cu" signal)
		(4 "In1.Cu" power)
		(6 "In2.Cu" mixed)
		(8 "In3.Cu" power)
		(10 "In4.Cu" mixed)
		(12 "In5.Cu" power)
		(14 "In6.Cu" mixed)
		(16 "In7.Cu" power)
		(18 "In8.Cu" power)
		(20 "In9.Cu" mixed)
		(22 "In10.Cu" power)
		(2 "B.Cu" signal)
		(9 "F.Adhes" user "F.Adhesive")
		(11 "B.Adhes" user "B.Adhesive")
		(13 "F.Paste" user)
		(15 "B.Paste" user)
		(5 "F.SilkS" user "F.Silkscreen")
		(7 "B.SilkS" user "B.Silkscreen")
		(1 "F.Mask" user)
		(3 "B.Mask" user)
		(17 "Dwgs.User" user "User.Drawings")
		(19 "Cmts.User" user "User.Comments")
		(21 "Eco1.User" user "User.Eco1")
		(23 "Eco2.User" user "User.Eco2")
		(25 "Edge.Cuts" user)
		(27 "Margin" user)
		(31 "F.CrtYd" user "F.Courtyard")
		(29 "B.CrtYd" user "B.Courtyard")
		(35 "F.Fab" user)
		(33 "B.Fab" user)
	)
	(footprint "antmicro-footprints:C_0402_1005Metric_EIA"
		(layer "B.Cu")
		(at 180 162.5 90)
		(descr "Capacitor SMD 0402 (1005 Metric), square (rectangular) end terminal, IPC_7351 nominal, (Body size source: IPC-SM-782 page 76, https://www.pcb-3d.com/wordpress/wp-content/uploads/ipc-sm-782a_amendment_1_and_2.pdf)")
		(tags "capacitor 0402")
		(property "Reference" "C83"
			(at -3.3 0.45 90)
			(layer "B.SilkS")
			(effects
				(font
					(size 0.7 0.7)
					(thickness 0.15)
				)
				(justify right bottom mirror)
			)
		)
		(property "Value" "C_100n_0402"
			(at 0 -1.169 90)
			(layer "B.Fab")
			(effects
				(font
					(size 0.7 0.7)
					(thickness 0.15)
				)
				(justify right bottom mirror)
			)
		)
		(property "Datasheet" "https://www.murata.com/products/productdetail?partno=GRM155R61H104KE14%23"
			(at 0 0 90)
			(layer "F.Fab")
			(hide yes)
			(effects
				(font
					(size 1.27 1.27)
					(thickness 0.15)
				)
			)
		)
		(property "MPN" "GRM155R61H104KE14D"
			(at 0 0 90)
			(unlocked yes)
			(layer "B.Fab")
			(hide yes)
			(effects
				(font
					(size 1 1)
					(thickness 0.15)
				)
				(justify mirror)
			)
		)
		(property "Manufacturer" "Murata"
			(at 0 0 90)
			(unlocked yes)
			(layer "B.Fab")
			(hide yes)
			(effects
				(font
					(size 1 1)
					(thickness 0.15)
				)
				(justify mirror)
			)
		)
		(property "License" "Apache-2.0"
			(at 0 0 90)
			(unlocked yes)
			(layer "B.Fab")
			(hide yes)
			(effects
				(font
					(size 1 1)
					(thickness 0.15)
				)
				(justify mirror)
			)
		)
		(property "Author" "Antmicro"
			(at 0 0 90)
			(unlocked yes)
			(layer "B.Fab")
			(hide yes)
			(effects
				(font
					(size 1 1)
					(thickness 0.15)
				)
				(justify mirror)
			)
		)
		(property "Val" "100n"
			(at 0 0 90)
			(unlocked yes)
			(layer "B.Fab")
			(hide yes)
			(effects
				(font
					(size 1 1)
					(thickness 0.15)
				)
				(justify mirror)
			)
		)
		(property "Voltage" "50V"
			(at 0 0 90)
			(unlocked yes)
			(layer "B.Fab")
			(hide yes)
			(effects
				(font
					(size 1 1)
					(thickness 0.15)
				)
				(justify mirror)
			)
		)
		(property "Dielectric" "X5R"
			(at 0 0 90)
			(unlocked yes)
			(layer "B.Fab")
			(hide yes)
			(effects
				(font
					(size 1 1)
					(thickness 0.15)
				)
				(justify mirror)
			)
		)
		(sheetname "/FPGA power/")
		(sheetfile "fpga-power.kicad_sch")
		(attr smd)
		(fp_rect
			(start -0.95 0.45)
			(end 0.95 -0.45)
			(stroke
				(width 0.05)
				(type default)
			)
			(fill no)
			(layer "B.CrtYd")
		)
		(fp_line
			(start 0.498 -0.248)
			(end -0.5 -0.248)
			(stroke
				(width 0.15)
				(type solid)
			)
			(layer "B.Fab")
		)
		(fp_line
			(start -0.5 -0.248)
			(end -0.5 0.25)
			(stroke
				(width 0.15)
				(type solid)
			)
			(layer "B.Fab")
		)
		(fp_line
			(start 0.498 0.25)
			(end 0.498 -0.248)
			(stroke
				(width 0.15)
				(type solid)
			)
			(layer "B.Fab")
		)
		(fp_line
			(start -0.5 0.25)
			(end 0.498 0.25)
			(stroke
				(width 0.15)
				(type solid)
			)
			(layer "B.Fab")
		)
		(fp_text user "${REFERENCE}"
			(at -0.9656 -3.169 270)
			(layer "B.Fab")
			(effects
				(font
					(size 0.7 0.7)
					(thickness 0.15)
				)
				(justify left bottom mirror)
			)
		)
		(fp_text user "License: Apache-2.0"
			(at -0.9656 -4.369 270)
			(layer "B.Fab")
			(effects
				(font
					(size 0.7 0.7)
					(thickness 0.15)
				)
				(justify left bottom mirror)
			)
		)
		(fp_text user "Author: Antmicro"
			(at -0.9656 -5.569 270)
			(layer "B.Fab")
			(effects
				(font
					(size 0.7 0.7)
					(thickness 0.15)
				)
				(justify left bottom mirror)
			)
		)
		(pad "1" smd roundrect
			(at -0.5 0)
			(size 0.6 0.6)
			(layers "B.Cu" "B.Mask" "B.Paste")
			(roundrect_rratio 0.25)
			(net 1 "GND")
			(pintype "passive")
		)
		(pad "2" smd roundrect
			(at 0.498 0 90)
			(size 0.6 0.6)
			(layers "B.Cu" "B.Mask" "B.Paste")
			(roundrect_rratio 0.25)
			(net 172 "+1V2_MGTAVTT")
			(pintype "passive")
		)
	)
	(footprint "antmicro-footprints:SC70-3"
		(layer "B.Cu")
		(at 250.375 120.275 90)
		(property "Reference" "Q25"
			(at 0.115 -3.435 180)
			(layer "B.SilkS")
			(effects
				(font
					(size 0.7 0.7)
					(thickness 0.15)
				)
				(justify right bottom mirror)
			)
		)
		(property "Value" "BSS138PW"
			(at 0 -2.3 90)
			(layer "B.Fab")
			(effects
				(font
					(size 0.7 0.7)
					(thickness 0.15)
				)
				(justify right bottom mirror)
			)
		)
		(property "Datasheet" "https://assets.nexperia.com/documents/data-sheet/BSS138PW.pdf"
			(at 0 0 90)
			(layer "F.Fab")
			(hide yes)
			(effects
				(font
					(size 1.27 1.27)
					(thickness 0.15)
				)
			)
		)
		(property "MPN" "BSS138PW"
			(at 0 0 90)
			(unlocked yes)
			(layer "B.Fab")
			(hide yes)
			(effects
				(font
					(size 1 1)
					(thickness 0.15)
				)
				(justify mirror)
			)
		)
		(property "Manufacturer" "Nexperia"
			(at 0 0 90)
			(unlocked yes)
			(layer "B.Fab")
			(hide yes)
			(effects
				(font
					(size 1 1)
					(thickness 0.15)
				)
				(justify mirror)
			)
		)
		(property "Author" "Antmicro"
			(at 0 0 90)
			(unlocked yes)
			(layer "B.Fab")
			(hide yes)
			(effects
				(font
					(size 1 1)
					(thickness 0.15)
				)
				(justify mirror)
			)
		)
		(property "License" "Apache-2.0"
			(at 0 0 90)
			(unlocked yes)
			(layer "B.Fab")
			(hide yes)
			(effects
				(font
					(size 1 1)
					(thickness 0.15)
				)
				(justify mirror)
			)
		)
		(sheetname "/DDR5 RDIMM/")
		(sheetfile "ddr5-rdimm.kicad_sch")
		(attr smd)
		(fp_line
			(start -0.3 -1)
			(end 0.627 -1.001)
			(stroke
				(width 0.15)
				(type solid)
			)
			(layer "B.SilkS")
		)
		(fp_line
			(start 0.627 -0.6)
			(end 0.627 -1.001)
			(stroke
				(width 0.15)
				(type solid)
			)
			(layer "B.SilkS")
		)
		(fp_line
			(start 0.627 0.6)
			(end 0.627 0.999)
			(stroke
				(width 0.15)
				(type solid)
			)
			(layer "B.SilkS")
		)
		(fp_line
			(start -0.3 1)
			(end 0.627 0.999)
			(stroke
				(width 0.15)
				(type solid)
			)
			(layer "B.SilkS")
		)
		(fp_line
			(start 0.9 -1.3)
			(end -0.9 -1.3)
			(stroke
				(width 0.05)
				(type solid)
			)
			(layer "B.CrtYd")
		)
		(fp_line
			(start -0.9 -1.3)
			(end -0.9 -1)
			(stroke
				(width 0.05)
				(type solid)
			)
			(layer "B.CrtYd")
		)
		(fp_line
			(start -0.9 -1)
			(end -1.4 -1)
			(stroke
				(width 0.05)
				(type solid)
			)
			(layer "B.CrtYd")
		)
		(fp_line
			(start -1.4 -1)
			(end -1.4 1)
			(stroke
				(width 0.05)
				(type solid)
			)
			(layer "B.CrtYd")
		)
		(fp_line
			(start 1.4 -0.4)
			(end 0.9 -0.4)
			(stroke
				(width 0.05)
				(type solid)
			)
			(layer "B.CrtYd")
		)
		(fp_line
			(start 0.9 -0.4)
			(end 0.9 -1.3)
			(stroke
				(width 0.05)
				(type solid)
			)
			(layer "B.CrtYd")
		)
		(fp_line
			(start 1.4 0.4)
			(end 1.4 -0.4)
			(stroke
				(width 0.05)
				(type solid)
			)
			(layer "B.CrtYd")
		)
		(fp_line
			(start 0.9 0.4)
			(end 1.4 0.4)
			(stroke
				(width 0.05)
				(type solid)
			)
			(layer "B.CrtYd")
		)
		(fp_line
			(start -0.9 1)
			(end -1.4 1)
			(stroke
				(width 0.05)
				(type solid)
			)
			(layer "B.CrtYd")
		)
		(fp_line
			(start 0.9 1.3)
			(end 0.9 0.4)
			(stroke
				(width 0.05)
				(type solid)
			)
			(layer "B.CrtYd")
		)
		(fp_line
			(start -0.9 1.3)
			(end -0.9 1)
			(stroke
				(width 0.05)
				(type solid)
			)
			(layer "B.CrtYd")
		)
		(fp_line
			(start -0.9 1.3)
			(end 0.9 1.3)
			(stroke
				(width 0.05)
				(type solid)
			)
			(layer "B.CrtYd")
		)
		(fp_rect
			(start -0.623 0.999)
			(end 0.627 -1.001)
			(stroke
				(width 0.15)
				(type solid)
			)
			(fill no)
			(layer "B.Fab")
		)
		(fp_text user "Author: Antmicro"
			(at -1.45 -5.782 270)
			(layer "B.Fab")
			(effects
				(font
					(size 0.7 0.7)
					(thickness 0.15)
				)
				(justify left bottom mirror)
			)
		)
		(fp_text user "License: Apache-2.0"
			(at -1.45 -6.782 270)
			(layer "B.Fab")
			(effects
				(font
					(size 0.7 0.7)
					(thickness 0.15)
				)
				(justify left bottom mirror)
			)
		)
		(fp_text user "${REFERENCE}"
			(at -1.45 -4.783 270)
			(layer "B.Fab")
			(effects
				(font
					(size 0.7 0.7)
					(thickness 0.15)
				)
				(justify left bottom mirror)
			)
		)
		(pad "1" smd rect
			(at -1.051 0.65)
			(size 0.6 0.6)
			(layers "B.Cu" "B.Mask" "B.Paste")
			(net 808 "VIN_BULK_EN")
			(pinfunction "G")
			(pintype "passive")
		)
		(pad "2" smd rect
			(at -1.051 -0.65)
			(size 0.6 0.6)
			(layers "B.Cu" "B.Mask" "B.Paste")
			(net 1 "GND")
			(pinfunction "S")
			(pintype "passive")
		)
		(pad "3" smd rect
			(at 1.05 0)
			(size 0.6 0.6)
			(layers "B.Cu" "B.Mask" "B.Paste")
			(net 806 "Net-(Q23-G)")
			(pinfunction "D")
			(pintype "passive")
		)
	)
	(footprint "antmicro-footprints:C_0402_1005Metric"
		(layer "B.Cu")
		(at 181.622499 193.2285 90)
		(descr "Capacitor SMD 0402")
		(tags "capacitor SMD 0402")
		(property "Reference" "C256"
			(at 0.994 0.403501 90)
			(layer "B.SilkS")
			(effects
				(font
					(size 0.7 0.7)
					(thickness 0.15)
				)
				(justify right bottom mirror)
			)
		)
		(property "Value" "C_100n_0402"
			(at -1.022927 -2.155213 90)
			(layer "B.Fab")
			(effects
				(font
					(size 0.7 0.7)
					(thickness 0.15)
				)
				(justify right bottom mirror)
			)
		)
		(property "Datasheet" "https://www.murata.com/products/productdetail?partno=GRM155R61H104KE14%23"
			(at 0 0 90)
			(layer "F.Fab")
			(hide yes)
			(effects
				(font
					(size 1.27 1.27)
					(thickness 0.15)
				)
			)
		)
		(property "Manufacturer" "Murata"
			(at 0 0 90)
			(unlocked yes)
			(layer "B.Fab")
			(hide yes)
			(effects
				(font
					(size 1 1)
					(thickness 0.15)
				)
				(justify mirror)
			)
		)
		(property "MPN" "GRM155R61H104KE14D"
			(at 0 0 90)
			(unlocked yes)
			(layer "B.Fab")
			(hide yes)
			(effects
				(font
					(size 1 1)
					(thickness 0.15)
				)
				(justify mirror)
			)
		)
		(property "Val" "100n"
			(at 0 0 90)
			(unlocked yes)
			(layer "B.Fab")
			(hide yes)
			(effects
				(font
					(size 1 1)
					(thickness 0.15)
				)
				(justify mirror)
			)
		)
		(property "License" "Apache-2.0"
			(at 0 0 90)
			(unlocked yes)
			(layer "B.Fab")
			(hide yes)
			(effects
				(font
					(size 1 1)
					(thickness 0.15)
				)
				(justify mirror)
			)
		)
		(property "Author" "Antmicro"
			(at 0 0 90)
			(unlocked yes)
			(layer "B.Fab")
			(hide yes)
			(effects
				(font
					(size 1 1)
					(thickness 0.15)
				)
				(justify mirror)
			)
		)
		(property "Voltage" "50V"
			(at 0 0 90)
			(unlocked yes)
			(layer "B.Fab")
			(hide yes)
			(effects
				(font
					(size 1 1)
					(thickness 0.15)
				)
				(justify mirror)
			)
		)
		(property "Dielectric" "X5R"
			(at 0 0 90)
			(unlocked yes)
			(layer "B.Fab")
			(hide yes)
			(effects
				(font
					(size 1 1)
					(thickness 0.15)
				)
				(justify mirror)
			)
		)
		(sheetname "/FPGA MGT Interface/")
		(sheetfile "fpga-mgt.kicad_sch")
		(attr smd)
		(fp_rect
			(start -0.925 0.47)
			(end 0.925 -0.47)
			(stroke
				(width 0.05)
				(type default)
			)
			(fill no)
			(layer "B.CrtYd")
		)
		(fp_line
			(start 0.504 -0.248)
			(end -0.494 -0.248)
			(stroke
				(width 0.15)
				(type solid)
			)
			(layer "B.Fab")
		)
		(fp_line
			(start -0.494 -0.248)
			(end -0.494 0.25)
			(stroke
				(width 0.15)
				(type solid)
			)
			(layer "B.Fab")
		)
		(fp_line
			(start 0.504 0.25)
			(end 0.504 -0.248)
			(stroke
				(width 0.15)
				(type solid)
			)
			(layer "B.Fab")
		)
		(fp_line
			(start -0.494 0.25)
			(end 0.504 0.25)
			(stroke
				(width 0.15)
				(type solid)
			)
			(layer "B.Fab")
		)
		(fp_text user "${REFERENCE}"
			(at -0.939 -4.599 270)
			(layer "B.Fab")
			(effects
				(font
					(size 0.7 0.7)
					(thickness 0.15)
				)
				(justify left bottom mirror)
			)
		)
		(fp_text user "License: Apache-2.0"
			(at -0.939 -5.799 270)
			(layer "B.Fab")
			(effects
				(font
					(size 0.7 0.7)
					(thickness 0.15)
				)
				(justify left bottom mirror)
			)
		)
		(fp_text user "Author: Antmicro"
			(at -0.939 -3.399 270)
			(layer "B.Fab")
			(effects
				(font
					(size 0.7 0.7)
					(thickness 0.15)
				)
				(justify left bottom mirror)
			)
		)
		(pad "1" smd roundrect
			(at -0.48 0 90)
			(size 0.59 0.64)
			(layers "B.Cu" "B.Mask" "B.Paste")
			(roundrect_rratio 0.25)
			(net 258 "/FPGA MGT Interface/PCIE.TXD4_P")
			(pintype "passive")
		)
		(pad "2" smd roundrect
			(at 0.48 0 90)
			(size 0.59 0.64)
			(layers "B.Cu" "B.Mask" "B.Paste")
			(roundrect_rratio 0.25)
			(net 566 "/FPGA MGT Interface/GTY_224_TX3_P")
			(pintype "passive")
		)
	)
	(footprint "antmicro-footprints:SC70-3"
		(layer "B.Cu")
		(at 244.86 120.275 90)
		(property "Reference" "Q28"
			(at 0.125 -3.33 180)
			(layer "B.SilkS")
			(effects
				(font
					(size 0.7 0.7)
					(thickness 0.15)
				)
				(justify right bottom mirror)
			)
		)
		(property "Value" "BSS138PW"
			(at 0 -2.3 90)
			(layer "B.Fab")
			(effects
				(font
					(size 0.7 0.7)
					(thickness 0.15)
				)
				(justify right bottom mirror)
			)
		)
		(property "Datasheet" "https://assets.nexperia.com/documents/data-sheet/BSS138PW.pdf"
			(at 0 0 90)
			(layer "F.Fab")
			(hide yes)
			(effects
				(font
					(size 1.27 1.27)
					(thickness 0.15)
				)
			)
		)
		(property "MPN" "BSS138PW"
			(at 0 0 90)
			(unlocked yes)
			(layer "B.Fab")
			(hide yes)
			(effects
				(font
					(size 1 1)
					(thickness 0.15)
				)
				(justify mirror)
			)
		)
		(property "Manufacturer" "Nexperia"
			(at 0 0 90)
			(unlocked yes)
			(layer "B.Fab")
			(hide yes)
			(effects
				(font
					(size 1 1)
					(thickness 0.15)
				)
				(justify mirror)
			)
		)
		(property "Author" "Antmicro"
			(at 0 0 90)
			(unlocked yes)
			(layer "B.Fab")
			(hide yes)
			(effects
				(font
					(size 1 1)
					(thickness 0.15)
				)
				(justify mirror)
			)
		)
		(property "License" "Apache-2.0"
			(at 0 0 90)
			(unlocked yes)
			(layer "B.Fab")
			(hide yes)
			(effects
				(font
					(size 1 1)
					(thickness 0.15)
				)
				(justify mirror)
			)
		)
		(sheetname "/Supply/")
		(sheetfile "supply.kicad_sch")
		(attr smd)
		(fp_line
			(start -0.3 -1)
			(end 0.627 -1.001)
			(stroke
				(width 0.15)
				(type solid)
			)
			(layer "B.SilkS")
		)
		(fp_line
			(start 0.627 -0.6)
			(end 0.627 -1.001)
			(stroke
				(width 0.15)
				(type solid)
			)
			(layer "B.SilkS")
		)
		(fp_line
			(start 0.627 0.6)
			(end 0.627 0.999)
			(stroke
				(width 0.15)
				(type solid)
			)
			(layer "B.SilkS")
		)
		(fp_line
			(start -0.3 1)
			(end 0.627 0.999)
			(stroke
				(width 0.15)
				(type solid)
			)
			(layer "B.SilkS")
		)
		(fp_line
			(start 0.9 -1.3)
			(end -0.9 -1.3)
			(stroke
				(width 0.05)
				(type solid)
			)
			(layer "B.CrtYd")
		)
		(fp_line
			(start -0.9 -1.3)
			(end -0.9 -1)
			(stroke
				(width 0.05)
				(type solid)
			)
			(layer "B.CrtYd")
		)
		(fp_line
			(start -0.9 -1)
			(end -1.4 -1)
			(stroke
				(width 0.05)
				(type solid)
			)
			(layer "B.CrtYd")
		)
		(fp_line
			(start -1.4 -1)
			(end -1.4 1)
			(stroke
				(width 0.05)
				(type solid)
			)
			(layer "B.CrtYd")
		)
		(fp_line
			(start 1.4 -0.4)
			(end 0.9 -0.4)
			(stroke
				(width 0.05)
				(type solid)
			)
			(layer "B.CrtYd")
		)
		(fp_line
			(start 0.9 -0.4)
			(end 0.9 -1.3)
			(stroke
				(width 0.05)
				(type solid)
			)
			(layer "B.CrtYd")
		)
		(fp_line
			(start 1.4 0.4)
			(end 1.4 -0.4)
			(stroke
				(width 0.05)
				(type solid)
			)
			(layer "B.CrtYd")
		)
		(fp_line
			(start 0.9 0.4)
			(end 1.4 0.4)
			(stroke
				(width 0.05)
				(type solid)
			)
			(layer "B.CrtYd")
		)
		(fp_line
			(start -0.9 1)
			(end -1.4 1)
			(stroke
				(width 0.05)
				(type solid)
			)
			(layer "B.CrtYd")
		)
		(fp_line
			(start 0.9 1.3)
			(end 0.9 0.4)
			(stroke
				(width 0.05)
				(type solid)
			)
			(layer "B.CrtYd")
		)
		(fp_line
			(start -0.9 1.3)
			(end -0.9 1)
			(stroke
				(width 0.05)
				(type solid)
			)
			(layer "B.CrtYd")
		)
		(fp_line
			(start -0.9 1.3)
			(end 0.9 1.3)
			(stroke
				(width 0.05)
				(type solid)
			)
			(layer "B.CrtYd")
		)
		(fp_rect
			(start -0.623 0.999)
			(end 0.627 -1.001)
			(stroke
				(width 0.15)
				(type solid)
			)
			(fill no)
			(layer "B.Fab")
		)
		(fp_text user "License: Apache-2.0"
			(at -1.45 -6.782 270)
			(layer "B.Fab")
			(effects
				(font
					(size 0.7 0.7)
					(thickness 0.15)
				)
				(justify left bottom mirror)
			)
		)
		(fp_text user "Author: Antmicro"
			(at -1.45 -5.782 270)
			(layer "B.Fab")
			(effects
				(font
					(size 0.7 0.7)
					(thickness 0.15)
				)
				(justify left bottom mirror)
			)
		)
		(fp_text user "${REFERENCE}"
			(at -1.45 -4.783 270)
			(layer "B.Fab")
			(effects
				(font
					(size 0.7 0.7)
					(thickness 0.15)
				)
				(justify left bottom mirror)
			)
		)
		(pad "1" smd rect
			(at -1.051 0.65)
			(size 0.6 0.6)
			(layers "B.Cu" "B.Mask" "B.Paste")
			(net 812 "Heater_PWM")
			(pinfunction "G")
			(pintype "passive")
		)
		(pad "2" smd rect
			(at -1.051 -0.65)
			(size 0.6 0.6)
			(layers "B.Cu" "B.Mask" "B.Paste")
			(net 1 "GND")
			(pinfunction "S")
			(pintype "passive")
		)
		(pad "3" smd rect
			(at 1.05 0)
			(size 0.6 0.6)
			(layers "B.Cu" "B.Mask" "B.Paste")
			(net 813 "Net-(Q28-D)")
			(pinfunction "D")
			(pintype "passive")
		)
	)
)
